# Knox_PTB_4Layer_Stackup_20120629_final.xlsx — Wistron (pcb-stackup)
| Board Number: |  |  | 12523-SA |  |  |  |  |  |
| Model Name: |  |  | KNOX_PTB |  |  |  |  |  |
| Layer Count: |  |  | 4 Layer |  |  |  |  |  |
| Date: |  |  | 41089 |  |  |  |  |  |
| Material: |  |  | FR4(Lead-Free, OSP, Tg:150) |  |  |  | Single End |  |
| CCL/PP type: |  |  | IT158, TU662, NP155F |  |  | Imp | 50 |  |
| Customer: |  |  | <name> |  |  | Variation | Inner  +/- 5ohm / Outer +/- 5ohm |  |
| EE Engineer: |  |  | <name> |  |  | Bus | Misc.I/O |  |
| SI Engineer: |  |  | <name> |  |  |  |  |  |
|  |  |  |  |  |  | Type | SE |  |
| Layer |  |  |  | Thickness | Er | Layers | 1,4 |  |
|  |  |  | Cu oz | Wistron | Wistron |  | Wistron |  |
|  | Mask |  |  | 0.5 | 3.4 |  | Width | Imp |
| S1 | Signal |  | 1.5 | 1.7 |  | S1 | 5.5 | 52.38 |
|  | Prepreg |  |  | 3.5 | 3.7 |  |  |  |
| P2 | PWR | GND | 2 oz | 2.6 |  | P2 |  |  |
|  | Core |  |  | 47 | 4.2 |  |  |  |
| P3 | PWR | GND | 2 oz | 2.6 |  | P3 |  |  |
|  | Prepreg |  |  | 3.5 | 3.7 |  |  |  |
| S4 | Signal |  | 1.5 | 1.7 |  | S4 | 5.5 | 52.38 |
|  | Mask |  |  | 0.5 | 3.4 |  |  |  |
| Target = 62 mil |  |  |  | 63.6 |  |  |  |  |
| Note: | 1. Unit is mil |  |  |  |  |  |  |  |
|  | 2. The variation of total thickness is +/- 10% |  |  |  |  |  |  |  |
|  | 3. Min hole copper thickness is 1.0 mil |  |  |  |  |  |  |  |
|  | 4. Min surface copper thickness 1.5 mil |  |  |  |  |  |  |  |
